# S9S_MB_2U (Grand Teton) — schematic netlist excerpt (pin names and nets, part order shuffled) for the footprints in the layout excerpt that follows; sources: Cadence DE-HDL packaged netlist, KiCad conversion of 03242023_DA0F0TMBIJ0_F0T_Motherboard_J_brd_V01_OCP.brd

PC273_P0_3  Q_CAP  2.2UF 10V 10% X6S  pkg C0402  page 268 : A = PVCCIN_CPU0_PVCC ; B = GND
R3005  Q_RES  18K 1% CHIP  pkg 0402LF  page 250 : A = P5V ; B = P5V_ADC

(kicad_pcb
	(version 20260206)
	(generator "pcbnew")
	(generator_version "10.0")
	(general
		(thickness 1.6)
		(legacy_teardrops no)
	)
	(paper "A4")
	(title_block
		(title "03242023_DA0F0TMBIJ0_F0T_Motherboard_J_brd_V01_OCP.brd")
		(comment 1 "Grand Teton / footprints 19-20 of 6105")
	)
	(layers
		(0 "F.Cu" signal "TOP")
		(4 "In1.Cu" signal "GND")
		(6 "In2.Cu" signal "IN1")
		(8 "In3.Cu" signal "GND1")
		(10 "In4.Cu" signal "IN2")
		(12 "In5.Cu" signal "GND2")
		(14 "In6.Cu" signal "IN3")
		(16 "In7.Cu" signal "GND3")
		(18 "In8.Cu" signal "VCC")
		(20 "In9.Cu" signal "VCC1")
		(22 "In10.Cu" signal "GND4")
		(24 "In11.Cu" signal "IN4")
		(26 "In12.Cu" signal "GND5")
		(28 "In13.Cu" signal "IN5")
		(30 "In14.Cu" signal "GND6")
		(32 "In15.Cu" signal "IN6")
		(34 "In16.Cu" signal "GND7")
		(2 "B.Cu" signal "BOTTOM")
		(9 "F.Adhes" user "F.Adhesive")
		(11 "B.Adhes" user "B.Adhesive")
		(13 "F.Paste" user "Package Geometry/Pastemask Top")
		(15 "B.Paste" user "Package Geometry/Pastemask Bottom")
		(5 "F.SilkS" user "Ref Des/Silkscreen Top")
		(7 "B.SilkS" user "Ref Des/Silkscreen Bottom")
		(1 "F.Mask" user "Board Geometry/Soldermask Top")
		(3 "B.Mask" user "Board Geometry/Soldermask Bottom")
		(17 "Dwgs.User" user "User.Drawings")
		(19 "Cmts.User" user "User.Comments")
		(21 "Eco1.User" user "User.Eco1")
		(23 "Eco2.User" user "User.Eco2")
		(25 "Edge.Cuts" user "Board Geometry/Outline")
		(27 "Margin" user)
		(31 "F.CrtYd" user "Package Geometry/Place Bound Top")
		(29 "B.CrtYd" user "Package Geometry/Place Bound Bottom")
		(35 "F.Fab" user "Ref Des/Assembly Top")
		(33 "B.Fab" user "Ref Des/Assembly Bottom")
	)
	(footprint ""
		(layer "F.Cu")
		(at 46.582584 -109.444282 180)
		(property "Reference" "R3005"
			(at 0 0 180)
			(layer "F.SilkS")
			(hide yes)
			(effects
				(font
					(size 1.27 1.27)
				)
			)
		)
		(property "Value" ""
			(at 0 0 180)
			(layer "F.Fab")
			(effects
				(font
					(size 1.27 1.27)
				)
			)
		)
		(duplicate_pad_numbers_are_jumpers no)
		(fp_line
			(start 0.7874 0.4064)
			(end -0.7874 0.4064)
			(stroke
				(width 0.1524)
				(type default)
			)
			(layer "F.SilkS")
		)
		(fp_line
			(start 0.7874 -0.4064)
			(end 0.7874 0.4064)
			(stroke
				(width 0.1524)
				(type default)
			)
			(layer "F.SilkS")
		)
		(fp_line
			(start -0.7874 0.4064)
			(end -0.7874 -0.4064)
			(stroke
				(width 0.1524)
				(type default)
			)
			(layer "F.SilkS")
		)
		(fp_line
			(start -0.7874 -0.4064)
			(end 0.7874 -0.4064)
			(stroke
				(width 0.1524)
				(type default)
			)
			(layer "F.SilkS")
		)
		(fp_line
			(start 0.67945 0.3048)
			(end 0.120396 0.3048)
			(stroke
				(width 0.1)
				(type default)
			)
			(layer "F.Fab")
		)
		(fp_line
			(start 0.67945 -0.3048)
			(end 0.67945 0.3048)
			(stroke
				(width 0.1)
				(type default)
			)
			(layer "F.Fab")
		)
		(fp_line
			(start 0.12065 -0.2794)
			(end 0.12065 -0.3048)
			(stroke
				(width 0.1)
				(type default)
			)
			(layer "F.Fab")
		)
		(fp_line
			(start 0.12065 -0.3048)
			(end 0.67945 -0.3048)
			(stroke
				(width 0.1)
				(type default)
			)
			(layer "F.Fab")
		)
		(fp_line
			(start 0.120396 0.3048)
			(end 0.120396 0.2794)
			(stroke
				(width 0.1)
				(type default)
			)
			(layer "F.Fab")
		)
		(fp_line
			(start 0.120396 0.2794)
			(end -0.12065 0.2794)
			(stroke
				(width 0.1)
				(type default)
			)
			(layer "F.Fab")
		)
		(fp_line
			(start -0.12065 0.3048)
			(end -0.67945 0.3048)
			(stroke
				(width 0.1)
				(type default)
			)
			(layer "F.Fab")
		)
		(fp_line
			(start -0.12065 0.2794)
			(end -0.12065 0.3048)
			(stroke
				(width 0.1)
				(type default)
			)
			(layer "F.Fab")
		)
		(fp_line
			(start -0.12065 -0.2794)
			(end 0.12065 -0.2794)
			(stroke
				(width 0.1)
				(type default)
			)
			(layer "F.Fab")
		)
		(fp_line
			(start -0.12065 -0.305054)
			(end -0.12065 -0.2794)
			(stroke
				(width 0.1)
				(type default)
			)
			(layer "F.Fab")
		)
		(fp_line
			(start -0.67945 0.3048)
			(end -0.67945 -0.305054)
			(stroke
				(width 0.1)
				(type default)
			)
			(layer "F.Fab")
		)
		(fp_line
			(start -0.67945 -0.305054)
			(end -0.12065 -0.305054)
			(stroke
				(width 0.1)
				(type default)
			)
			(layer "F.Fab")
		)
		(pad "1" smd circle
			(at -0.40005 0 180)
			(size 0 0)
			(layers "F.Cu" "F.Mask" "F.Paste")
			(net "P5V")
		)
		(pad "2" smd circle
			(at 0.40005 0 180)
			(size 0 0)
			(layers "F.Cu" "F.Mask" "F.Paste")
			(net "P5V_ADC")
		)
	)
	(footprint ""
		(layer "F.Cu")
		(at 357.683816 -333.525368 -90)
		(property "Reference" "PC273_P0_3"
			(at 0 0 270)
			(layer "F.SilkS")
			(hide yes)
			(effects
				(font
					(size 1.27 1.27)
				)
			)
		)
		(property "Value" ""
			(at 0 0 270)
			(layer "F.Fab")
			(effects
				(font
					(size 1.27 1.27)
				)
			)
		)
		(duplicate_pad_numbers_are_jumpers no)
		(fp_line
			(start -0.7874 0.4064)
			(end -0.7874 -0.4064)
			(stroke
				(width 0.1524)
				(type default)
			)
			(layer "F.SilkS")
		)
		(fp_line
			(start 0.7874 0.4064)
			(end -0.7874 0.4064)
			(stroke
				(width 0.1524)
				(type default)
			)
			(layer "F.SilkS")
		)
		(fp_line
			(start -0.7874 -0.4064)
			(end 0.7874 -0.4064)
			(stroke
				(width 0.1524)
				(type default)
			)
			(layer "F.SilkS")
		)
		(fp_line
			(start 0.7874 -0.4064)
			(end 0.7874 0.4064)
			(stroke
				(width 0.1524)
				(type default)
			)
			(layer "F.SilkS")
		)
		(fp_line
			(start -0.67945 0.3048)
			(end -0.67945 -0.305054)
			(stroke
				(width 0.1)
				(type default)
			)
			(layer "F.Fab")
		)
		(fp_line
			(start -0.12065 0.3048)
			(end -0.67945 0.3048)
			(stroke
				(width 0.1)
				(type default)
			)
			(layer "F.Fab")
		)
		(fp_line
			(start 0.120396 0.3048)
			(end 0.120396 0.2794)
			(stroke
				(width 0.1)
				(type default)
			)
			(layer "F.Fab")
		)
		(fp_line
			(start 0.67945 0.3048)
			(end 0.120396 0.3048)
			(stroke
				(width 0.1)
				(type default)
			)
			(layer "F.Fab")
		)
		(fp_line
			(start -0.12065 0.2794)
			(end -0.12065 0.3048)
			(stroke
				(width 0.1)
				(type default)
			)
			(layer "F.Fab")
		)
		(fp_line
			(start 0.120396 0.2794)
			(end -0.12065 0.2794)
			(stroke
				(width 0.1)
				(type default)
			)
			(layer "F.Fab")
		)
		(fp_line
			(start -0.12065 -0.2794)
			(end 0.12065 -0.2794)
			(stroke
				(width 0.1)
				(type default)
			)
			(layer "F.Fab")
		)
		(fp_line
			(start 0.12065 -0.2794)
			(end 0.12065 -0.3048)
			(stroke
				(width 0.1)
				(type default)
			)
			(layer "F.Fab")
		)
		(fp_line
			(start 0.12065 -0.3048)
			(end 0.67945 -0.3048)
			(stroke
				(width 0.1)
				(type default)
			)
			(layer "F.Fab")
		)
		(fp_line
			(start 0.67945 -0.3048)
			(end 0.67945 0.3048)
			(stroke
				(width 0.1)
				(type default)
			)
			(layer "F.Fab")
		)
		(fp_line
			(start -0.67945 -0.305054)
			(end -0.12065 -0.305054)
			(stroke
				(width 0.1)
				(type default)
			)
			(layer "F.Fab")
		)
		(fp_line
			(start -0.12065 -0.305054)
			(end -0.12065 -0.2794)
			(stroke
				(width 0.1)
				(type default)
			)
			(layer "F.Fab")
		)
		(pad "1" smd circle
			(at -0.40005 0 270)
			(size 0 0)
			(layers "F.Cu" "F.Mask" "F.Paste")
			(net "PVCCIN_CPU0_PVCC")
		)
		(pad "2" smd circle
			(at 0.40005 0 270)
			(size 0 0)
			(layers "F.Cu" "F.Mask" "F.Paste")
			(net "GND")
		)
	)
)
